(kicad_pcb
	(version 20260206)
	(generator "pcbnew")
	(generator_version "10.0")
	(general
		(thickness 1.6)
		(legacy_teardrops no)
	)
	(paper "A4")
	(title_block
		(title "01162023_DA0F0TEBIF0_F0T_Expander_BD_F_brd_V02_OCP.brd")
		(comment 1 "Grand Teton / footprints 9593-9600 of 9728")
	)
	(layers
		(0 "F.Cu" signal "TOP")
		(4 "In1.Cu" signal "GND")
		(6 "In2.Cu" signal "VCC")
		(8 "In3.Cu" signal "VCC1")
		(10 "In4.Cu" signal "GND1")
		(12 "In5.Cu" signal "IN1")
		(14 "In6.Cu" signal "GND2")
		(16 "In7.Cu" signal "IN2")
		(18 "In8.Cu" signal "GND3")
		(20 "In9.Cu" signal "IN3")
		(22 "In10.Cu" signal "GND4")
		(24 "In11.Cu" signal "IN4")
		(26 "In12.Cu" signal "GND5")
		(28 "In13.Cu" signal "IN5")
		(30 "In14.Cu" signal "GND6")
		(32 "In15.Cu" signal "IN6")
		(34 "In16.Cu" signal "GND7")
		(2 "B.Cu" signal "BOTTOM")
		(9 "F.Adhes" user "F.Adhesive")
		(11 "B.Adhes" user "B.Adhesive")
		(13 "F.Paste" user "Package Geometry/Pastemask Top")
		(15 "B.Paste" user "Package Geometry/Pastemask Bottom")
		(5 "F.SilkS" user "Ref Des/Silkscreen Top")
		(7 "B.SilkS" user "Ref Des/Silkscreen Bottom")
		(1 "F.Mask" user "Board Geometry/Soldermask Top")
		(3 "B.Mask" user "Board Geometry/Soldermask Bottom")
		(17 "Dwgs.User" user "User.Drawings")
		(19 "Cmts.User" user "User.Comments")
		(21 "Eco1.User" user "User.Eco1")
		(23 "Eco2.User" user "User.Eco2")
		(25 "Edge.Cuts" user "Board Geometry/Outline")
		(27 "Margin" user)
		(31 "F.CrtYd" user "Package Geometry/Place Bound Top")
		(29 "B.CrtYd" user "Package Geometry/Place Bound Bottom")
		(35 "F.Fab" user "Ref Des/Assembly Top")
		(33 "B.Fab" user "Ref Des/Assembly Bottom")
	)
	(footprint ""
		(layer "B.Cu")
		(at 157.699964 -288.774886 90)
		(property "Reference" "R6158"
			(at 0 0 90)
			(layer "B.SilkS")
			(hide yes)
			(effects
				(font
					(size 1.27 1.27)
				)
				(justify mirror)
			)
		)
		(property "Value" ""
			(at 0 0 90)
			(layer "B.Fab")
			(effects
				(font
					(size 1.27 1.27)
				)
				(justify mirror)
			)
		)
		(duplicate_pad_numbers_are_jumpers no)
		(fp_line
			(start 0.7874 -0.4064)
			(end -0.7874 -0.4064)
			(stroke
				(width 0.1524)
				(type default)
			)
			(layer "B.SilkS")
		)
		(fp_line
			(start -0.7874 -0.4064)
			(end -0.7874 0.4064)
			(stroke
				(width 0.1524)
				(type default)
			)
			(layer "B.SilkS")
		)
		(fp_line
			(start 0.7874 0.4064)
			(end 0.7874 -0.4064)
			(stroke
				(width 0.1524)
				(type default)
			)
			(layer "B.SilkS")
		)
		(fp_line
			(start -0.7874 0.4064)
			(end 0.7874 0.4064)
			(stroke
				(width 0.1524)
				(type default)
			)
			(layer "B.SilkS")
		)
		(fp_line
			(start 0.67945 -0.305054)
			(end 0.12065 -0.305054)
			(stroke
				(width 0.1)
				(type default)
			)
			(layer "B.Fab")
		)
		(fp_line
			(start 0.12065 -0.305054)
			(end 0.12065 -0.2794)
			(stroke
				(width 0.1)
				(type default)
			)
			(layer "B.Fab")
		)
		(fp_line
			(start -0.12065 -0.3048)
			(end -0.67945 -0.3048)
			(stroke
				(width 0.1)
				(type default)
			)
			(layer "B.Fab")
		)
		(fp_line
			(start -0.67945 -0.3048)
			(end -0.67945 0.3048)
			(stroke
				(width 0.1)
				(type default)
			)
			(layer "B.Fab")
		)
		(fp_line
			(start 0.12065 -0.2794)
			(end -0.12065 -0.2794)
			(stroke
				(width 0.1)
				(type default)
			)
			(layer "B.Fab")
		)
		(fp_line
			(start -0.12065 -0.2794)
			(end -0.12065 -0.3048)
			(stroke
				(width 0.1)
				(type default)
			)
			(layer "B.Fab")
		)
		(fp_line
			(start 0.12065 0.2794)
			(end 0.12065 0.3048)
			(stroke
				(width 0.1)
				(type default)
			)
			(layer "B.Fab")
		)
		(fp_line
			(start -0.120396 0.2794)
			(end 0.12065 0.2794)
			(stroke
				(width 0.1)
				(type default)
			)
			(layer "B.Fab")
		)
		(fp_line
			(start 0.67945 0.3048)
			(end 0.67945 -0.305054)
			(stroke
				(width 0.1)
				(type default)
			)
			(layer "B.Fab")
		)
		(fp_line
			(start 0.12065 0.3048)
			(end 0.67945 0.3048)
			(stroke
				(width 0.1)
				(type default)
			)
			(layer "B.Fab")
		)
		(fp_line
			(start -0.120396 0.3048)
			(end -0.120396 0.2794)
			(stroke
				(width 0.1)
				(type default)
			)
			(layer "B.Fab")
		)
		(fp_line
			(start -0.67945 0.3048)
			(end -0.120396 0.3048)
			(stroke
				(width 0.1)
				(type default)
			)
			(layer "B.Fab")
		)
		(pad "1" smd circle
			(at 0.40005 0 270)
			(size 0 0)
			(layers "B.Cu" "B.Mask" "B.Paste")
			(net "SPI_PEX1_CS_N")
		)
		(pad "2" smd circle
			(at -0.40005 0 270)
			(size 0 0)
			(layers "B.Cu" "B.Mask" "B.Paste")
			(net "P1V8_PEX")
		)
	)
	(footprint ""
		(layer "B.Cu")
		(at 135.941816 -204.060806 180)
		(property "Reference" "L7"
			(at 0 0 0)
			(layer "B.SilkS")
			(hide yes)
			(effects
				(font
					(size 1.27 1.27)
				)
				(justify mirror)
			)
		)
		(property "Value" ""
			(at 0 0 0)
			(layer "B.Fab")
			(effects
				(font
					(size 1.27 1.27)
				)
				(justify mirror)
			)
		)
		(duplicate_pad_numbers_are_jumpers no)
		(fp_line
			(start 1.27 0.5842)
			(end 1.27 -0.5842)
			(stroke
				(width 0.1524)
				(type default)
			)
			(layer "B.SilkS")
		)
		(fp_line
			(start 1.27 -0.5588)
			(end 1.27 -0.5842)
			(stroke
				(width 0.1524)
				(type default)
			)
			(layer "B.SilkS")
		)
		(fp_line
			(start 1.27 -0.5842)
			(end -1.27 -0.5842)
			(stroke
				(width 0.1524)
				(type default)
			)
			(layer "B.SilkS")
		)
		(fp_line
			(start -1.27 0.5842)
			(end 1.27 0.5842)
			(stroke
				(width 0.1524)
				(type default)
			)
			(layer "B.SilkS")
		)
		(fp_line
			(start -1.27 0.5842)
			(end -1.27 -0.5842)
			(stroke
				(width 0.1524)
				(type default)
			)
			(layer "B.SilkS")
		)
		(fp_line
			(start 1.194308 0.406654)
			(end 1.194308 -0.406654)
			(stroke
				(width 0.1)
				(type default)
			)
			(layer "B.Fab")
		)
		(fp_line
			(start 1.194308 -0.406654)
			(end 0.9144 -0.406654)
			(stroke
				(width 0.1)
				(type default)
			)
			(layer "B.Fab")
		)
		(fp_line
			(start 0.9144 0.508)
			(end 0.9144 0.406654)
			(stroke
				(width 0.1)
				(type default)
			)
			(layer "B.Fab")
		)
		(fp_line
			(start 0.9144 0.406654)
			(end 1.194308 0.406654)
			(stroke
				(width 0.1)
				(type default)
			)
			(layer "B.Fab")
		)
		(fp_line
			(start 0.9144 -0.406654)
			(end 0.9144 -0.508)
			(stroke
				(width 0.1)
				(type default)
			)
			(layer "B.Fab")
		)
		(fp_line
			(start 0.9144 -0.508)
			(end -0.9144 -0.508)
			(stroke
				(width 0.1)
				(type default)
			)
			(layer "B.Fab")
		)
		(fp_line
			(start -0.9144 0.508)
			(end 0.9144 0.508)
			(stroke
				(width 0.1)
				(type default)
			)
			(layer "B.Fab")
		)
		(fp_line
			(start -0.9144 0.4064)
			(end -0.9144 0.508)
			(stroke
				(width 0.1)
				(type default)
			)
			(layer "B.Fab")
		)
		(fp_line
			(start -0.9144 -0.406654)
			(end -1.1938 -0.406654)
			(stroke
				(width 0.1)
				(type default)
			)
			(layer "B.Fab")
		)
		(fp_line
			(start -0.9144 -0.508)
			(end -0.9144 -0.406654)
			(stroke
				(width 0.1)
				(type default)
			)
			(layer "B.Fab")
		)
		(fp_line
			(start -1.1938 0.4064)
			(end -0.9144 0.4064)
			(stroke
				(width 0.1)
				(type default)
			)
			(layer "B.Fab")
		)
		(fp_line
			(start -1.1938 -0.406654)
			(end -1.1938 0.4064)
			(stroke
				(width 0.1)
				(type default)
			)
			(layer "B.Fab")
		)
		(pad "1" smd rect
			(at 0.7366 0 90)
			(size 0.7112 0.8128)
			(layers "B.Cu" "B.Mask" "B.Paste")
			(net "P3V3_AUX")
		)
		(pad "2" smd rect
			(at -0.7366 0 90)
			(size 0.7112 0.8128)
			(layers "B.Cu" "B.Mask" "B.Paste")
			(net "P3V3_CLI_VPHY")
		)
	)
	(footprint ""
		(layer "B.Cu")
		(at 236.505496 -212.332824 90)
		(property "Reference" "R478"
			(at 0 0 90)
			(layer "B.SilkS")
			(hide yes)
			(effects
				(font
					(size 1.27 1.27)
				)
				(justify mirror)
			)
		)
		(property "Value" ""
			(at 0 0 90)
			(layer "B.Fab")
			(effects
				(font
					(size 1.27 1.27)
				)
				(justify mirror)
			)
		)
		(duplicate_pad_numbers_are_jumpers no)
		(fp_line
			(start 0.7874 -0.4064)
			(end -0.7874 -0.4064)
			(stroke
				(width 0.1524)
				(type default)
			)
			(layer "B.SilkS")
		)
		(fp_line
			(start -0.7874 -0.4064)
			(end -0.7874 0.4064)
			(stroke
				(width 0.1524)
				(type default)
			)
			(layer "B.SilkS")
		)
		(fp_line
			(start 0.7874 0.4064)
			(end 0.7874 -0.4064)
			(stroke
				(width 0.1524)
				(type default)
			)
			(layer "B.SilkS")
		)
		(fp_line
			(start -0.7874 0.4064)
			(end 0.7874 0.4064)
			(stroke
				(width 0.1524)
				(type default)
			)
			(layer "B.SilkS")
		)
		(fp_line
			(start 0.67945 -0.305054)
			(end 0.12065 -0.305054)
			(stroke
				(width 0.1)
				(type default)
			)
			(layer "B.Fab")
		)
		(fp_line
			(start 0.12065 -0.305054)
			(end 0.12065 -0.2794)
			(stroke
				(width 0.1)
				(type default)
			)
			(layer "B.Fab")
		)
		(fp_line
			(start -0.12065 -0.3048)
			(end -0.67945 -0.3048)
			(stroke
				(width 0.1)
				(type default)
			)
			(layer "B.Fab")
		)
		(fp_line
			(start -0.67945 -0.3048)
			(end -0.67945 0.3048)
			(stroke
				(width 0.1)
				(type default)
			)
			(layer "B.Fab")
		)
		(fp_line
			(start 0.12065 -0.2794)
			(end -0.12065 -0.2794)
			(stroke
				(width 0.1)
				(type default)
			)
			(layer "B.Fab")
		)
		(fp_line
			(start -0.12065 -0.2794)
			(end -0.12065 -0.3048)
			(stroke
				(width 0.1)
				(type default)
			)
			(layer "B.Fab")
		)
		(fp_line
			(start 0.12065 0.2794)
			(end 0.12065 0.3048)
			(stroke
				(width 0.1)
				(type default)
			)
			(layer "B.Fab")
		)
		(fp_line
			(start -0.120396 0.2794)
			(end 0.12065 0.2794)
			(stroke
				(width 0.1)
				(type default)
			)
			(layer "B.Fab")
		)
		(fp_line
			(start 0.67945 0.3048)
			(end 0.67945 -0.305054)
			(stroke
				(width 0.1)
				(type default)
			)
			(layer "B.Fab")
		)
		(fp_line
			(start 0.12065 0.3048)
			(end 0.67945 0.3048)
			(stroke
				(width 0.1)
				(type default)
			)
			(layer "B.Fab")
		)
		(fp_line
			(start -0.120396 0.3048)
			(end -0.120396 0.2794)
			(stroke
				(width 0.1)
				(type default)
			)
			(layer "B.Fab")
		)
		(fp_line
			(start -0.67945 0.3048)
			(end -0.120396 0.3048)
			(stroke
				(width 0.1)
				(type default)
			)
			(layer "B.Fab")
		)
		(pad "1" smd circle
			(at 0.40005 0 270)
			(size 0 0)
			(layers "B.Cu" "B.Mask" "B.Paste")
			(net "P1V2_AUX_SCALED")
		)
		(pad "2" smd circle
			(at -0.40005 0 270)
			(size 0 0)
			(layers "B.Cu" "B.Mask" "B.Paste")
			(net "GND")
		)
	)
	(footprint ""
		(layer "B.Cu")
		(at 105.287826 -319.420494 -90)
		(property "Reference" "R5785"
			(at 0 0 90)
			(layer "B.SilkS")
			(hide yes)
			(effects
				(font
					(size 1.27 1.27)
				)
				(justify mirror)
			)
		)
		(property "Value" ""
			(at 0 0 90)
			(layer "B.Fab")
			(effects
				(font
					(size 1.27 1.27)
				)
				(justify mirror)
			)
		)
		(duplicate_pad_numbers_are_jumpers no)
		(fp_line
			(start -2.576322 1.1303)
			(end 2.576322 1.1303)
			(stroke
				(width 0.1524)
				(type default)
			)
			(layer "B.SilkS")
		)
		(fp_line
			(start 2.576322 1.1303)
			(end 2.576322 -1.1303)
			(stroke
				(width 0.1524)
				(type default)
			)
			(layer "B.SilkS")
		)
		(fp_line
			(start -2.576322 -1.1303)
			(end -2.576322 1.1303)
			(stroke
				(width 0.1524)
				(type default)
			)
			(layer "B.SilkS")
		)
		(fp_line
			(start 2.576322 -1.1303)
			(end -2.576322 -1.1303)
			(stroke
				(width 0.1524)
				(type default)
			)
			(layer "B.SilkS")
		)
		(fp_line
			(start -1.649984 0.899922)
			(end -1.649984 -0.899922)
			(stroke
				(width 0.1)
				(type default)
			)
			(layer "B.Fab")
		)
		(fp_line
			(start 1.649984 0.899922)
			(end -1.649984 0.899922)
			(stroke
				(width 0.1)
				(type default)
			)
			(layer "B.Fab")
		)
		(fp_line
			(start -1.649984 -0.899922)
			(end 1.649984 -0.899922)
			(stroke
				(width 0.1)
				(type default)
			)
			(layer "B.Fab")
		)
		(fp_line
			(start 1.649984 -0.899922)
			(end 1.649984 0.899922)
			(stroke
				(width 0.1)
				(type default)
			)
			(layer "B.Fab")
		)
		(pad "1A" smd rect
			(at 1.700022 0 90)
			(size 1.4986 2.0066)
			(layers "B.Cu" "B.Mask" "B.Paste")
			(net "P0V8_PEX0")
		)
		(pad "1B" smd rect
			(at 1.077722 0 90)
			(size 0.254 0.508)
			(layers "B.Cu" "B.Mask" "B.Paste")
			(net "P0V8_PEX0")
		)
		(pad "2A" smd rect
			(at -1.700022 0 90)
			(size 1.4986 2.0066)
			(layers "B.Cu" "B.Mask" "B.Paste")
			(net "P0V8_SERDES_VDDA_PEX0")
		)
		(pad "2B" smd rect
			(at -1.077722 0 90)
			(size 0.254 0.508)
			(layers "B.Cu" "B.Mask" "B.Paste")
			(net "P0V8_SERDES_VDDA_PEX0")
		)
	)
	(footprint ""
		(layer "B.Cu")
		(at 56.799988 -290.199826 90)
		(property "Reference" "C1203"
			(at 0 0 90)
			(layer "B.SilkS")
			(hide yes)
			(effects
				(font
					(size 1.27 1.27)
				)
				(justify mirror)
			)
		)
		(property "Value" ""
			(at 0 0 90)
			(layer "B.Fab")
			(effects
				(font
					(size 1.27 1.27)
				)
				(justify mirror)
			)
		)
		(duplicate_pad_numbers_are_jumpers no)
		(fp_line
			(start 0.299974 -0.150114)
			(end -0.299974 -0.150114)
			(stroke
				(width 0.1)
				(type default)
			)
			(layer "B.Fab")
		)
		(fp_line
			(start -0.299974 -0.150114)
			(end -0.299974 0.150114)
			(stroke
				(width 0.1)
				(type default)
			)
			(layer "B.Fab")
		)
		(fp_line
			(start 0.299974 0.150114)
			(end 0.299974 -0.150114)
			(stroke
				(width 0.1)
				(type default)
			)
			(layer "B.Fab")
		)
		(fp_line
			(start -0.299974 0.150114)
			(end 0.299974 0.150114)
			(stroke
				(width 0.1)
				(type default)
			)
			(layer "B.Fab")
		)
		(pad "1" smd rect
			(at 0.2667 0 270)
			(size 0.3048 0.381)
			(layers "B.Cu" "B.Mask" "B.Paste")
			(net "P0V8_SERDES_VDDA_PEX0")
		)
		(pad "2" smd rect
			(at -0.2667 0 270)
			(size 0.3048 0.381)
			(layers "B.Cu" "B.Mask" "B.Paste")
			(net "GND")
		)
	)
	(footprint ""
		(layer "B.Cu")
		(at 213.730332 -223.382586 180)
		(property "Reference" "R4114"
			(at 0 0 0)
			(layer "B.SilkS")
			(hide yes)
			(effects
				(font
					(size 1.27 1.27)
				)
				(justify mirror)
			)
		)
		(property "Value" ""
			(at 0 0 0)
			(layer "B.Fab")
			(effects
				(font
					(size 1.27 1.27)
				)
				(justify mirror)
			)
		)
		(duplicate_pad_numbers_are_jumpers no)
		(fp_line
			(start 0.7874 0.4064)
			(end 0.7874 -0.4064)
			(stroke
				(width 0.1524)
				(type default)
			)
			(layer "B.SilkS")
		)
		(fp_line
			(start 0.7874 -0.4064)
			(end -0.7874 -0.4064)
			(stroke
				(width 0.1524)
				(type default)
			)
			(layer "B.SilkS")
		)
		(fp_line
			(start -0.7874 0.4064)
			(end 0.7874 0.4064)
			(stroke
				(width 0.1524)
				(type default)
			)
			(layer "B.SilkS")
		)
		(fp_line
			(start -0.7874 -0.4064)
			(end -0.7874 0.4064)
			(stroke
				(width 0.1524)
				(type default)
			)
			(layer "B.SilkS")
		)
		(fp_line
			(start 0.67945 0.3048)
			(end 0.67945 -0.305054)
			(stroke
				(width 0.1)
				(type default)
			)
			(layer "B.Fab")
		)
		(fp_line
			(start 0.67945 -0.305054)
			(end 0.12065 -0.305054)
			(stroke
				(width 0.1)
				(type default)
			)
			(layer "B.Fab")
		)
		(fp_line
			(start 0.12065 0.3048)
			(end 0.67945 0.3048)
			(stroke
				(width 0.1)
				(type default)
			)
			(layer "B.Fab")
		)
		(fp_line
			(start 0.12065 0.2794)
			(end 0.12065 0.3048)
			(stroke
				(width 0.1)
				(type default)
			)
			(layer "B.Fab")
		)
		(fp_line
			(start 0.12065 -0.2794)
			(end -0.12065 -0.2794)
			(stroke
				(width 0.1)
				(type default)
			)
			(layer "B.Fab")
		)
		(fp_line
			(start 0.12065 -0.305054)
			(end 0.12065 -0.2794)
			(stroke
				(width 0.1)
				(type default)
			)
			(layer "B.Fab")
		)
		(fp_line
			(start -0.120396 0.3048)
			(end -0.120396 0.2794)
			(stroke
				(width 0.1)
				(type default)
			)
			(layer "B.Fab")
		)
		(fp_line
			(start -0.120396 0.2794)
			(end 0.12065 0.2794)
			(stroke
				(width 0.1)
				(type default)
			)
			(layer "B.Fab")
		)
		(fp_line
			(start -0.12065 -0.2794)
			(end -0.12065 -0.3048)
			(stroke
				(width 0.1)
				(type default)
			)
			(layer "B.Fab")
		)
		(fp_line
			(start -0.12065 -0.3048)
			(end -0.67945 -0.3048)
			(stroke
				(width 0.1)
				(type default)
			)
			(layer "B.Fab")
		)
		(fp_line
			(start -0.67945 0.3048)
			(end -0.120396 0.3048)
			(stroke
				(width 0.1)
				(type default)
			)
			(layer "B.Fab")
		)
		(fp_line
			(start -0.67945 -0.3048)
			(end -0.67945 0.3048)
			(stroke
				(width 0.1)
				(type default)
			)
			(layer "B.Fab")
		)
		(pad "1" smd circle
			(at 0.40005 0)
			(size 0 0)
			(layers "B.Cu" "B.Mask" "B.Paste")
			(net "P3V3_AUX")
		)
		(pad "2" smd circle
			(at -0.40005 0)
			(size 0 0)
			(layers "B.Cu" "B.Mask" "B.Paste")
			(net "SMB_BIC_I2C6_SDA")
		)
	)
	(footprint ""
		(layer "B.Cu")
		(at 58.699908 -303.499774 -90)
		(property "Reference" "C2922"
			(at 0 0 90)
			(layer "B.SilkS")
			(hide yes)
			(effects
				(font
					(size 1.27 1.27)
				)
				(justify mirror)
			)
		)
		(property "Value" ""
			(at 0 0 90)
			(layer "B.Fab")
			(effects
				(font
					(size 1.27 1.27)
				)
				(justify mirror)
			)
		)
		(duplicate_pad_numbers_are_jumpers no)
		(fp_line
			(start -0.299974 0.150114)
			(end 0.299974 0.150114)
			(stroke
				(width 0.1)
				(type default)
			)
			(layer "B.Fab")
		)
		(fp_line
			(start 0.299974 0.150114)
			(end 0.299974 -0.150114)
			(stroke
				(width 0.1)
				(type default)
			)
			(layer "B.Fab")
		)
		(fp_line
			(start -0.299974 -0.150114)
			(end -0.299974 0.150114)
			(stroke
				(width 0.1)
				(type default)
			)
			(layer "B.Fab")
		)
		(fp_line
			(start 0.299974 -0.150114)
			(end -0.299974 -0.150114)
			(stroke
				(width 0.1)
				(type default)
			)
			(layer "B.Fab")
		)
		(pad "1" smd rect
			(at 0.2667 0 90)
			(size 0.3048 0.381)
			(layers "B.Cu" "B.Mask" "B.Paste")
			(net "P1V25_PEX0")
		)
		(pad "2" smd rect
			(at -0.2667 0 90)
			(size 0.3048 0.381)
			(layers "B.Cu" "B.Mask" "B.Paste")
			(net "GND")
		)
	)
	(footprint ""
		(layer "B.Cu")
		(at 417.450016 -296.37482 180)
		(property "Reference" "C1928"
			(at 0 0 0)
			(layer "B.SilkS")
			(hide yes)
			(effects
				(font
					(size 1.27 1.27)
				)
				(justify mirror)
			)
		)
		(property "Value" ""
			(at 0 0 0)
			(layer "B.Fab")
			(effects
				(font
					(size 1.27 1.27)
				)
				(justify mirror)
			)
		)
		(duplicate_pad_numbers_are_jumpers no)
		(fp_line
			(start 0.299974 0.150114)
			(end 0.299974 -0.150114)
			(stroke
				(width 0.1)
				(type default)
			)
			(layer "B.Fab")
		)
		(fp_line
			(start 0.299974 -0.150114)
			(end -0.299974 -0.150114)
			(stroke
				(width 0.1)
				(type default)
			)
			(layer "B.Fab")
		)
		(fp_line
			(start -0.299974 0.150114)
			(end 0.299974 0.150114)
			(stroke
				(width 0.1)
				(type default)
			)
			(layer "B.Fab")
		)
		(fp_line
			(start -0.299974 -0.150114)
			(end -0.299974 0.150114)
			(stroke
				(width 0.1)
				(type default)
			)
			(layer "B.Fab")
		)
		(pad "1" smd rect
			(at 0.2667 0)
			(size 0.3048 0.381)
			(layers "B.Cu" "B.Mask" "B.Paste")
			(net "P0V8_SERDES_VDDA_PEX3")
		)
		(pad "2" smd rect
			(at -0.2667 0)
			(size 0.3048 0.381)
			(layers "B.Cu" "B.Mask" "B.Paste")
			(net "GND")
		)
	)
)
